(kicad_pcb
	(version 20260206)
	(generator "pcbnew")
	(generator_version "10.0")
	(general
		(thickness 1.6)
		(legacy_teardrops no)
	)
	(paper "A4")
	(title_block
		(title "01162023_DA0F0TEBIF0_F0T_Expander_BD_F_brd_V02_OCP.brd")
		(comment 1 "Grand Teton / footprint 6619 of 9728 (PEX0), pads 2357-2397 of 2397")
	)
	(layers
		(0 "F.Cu" signal "TOP")
		(4 "In1.Cu" signal "GND")
		(6 "In2.Cu" signal "VCC")
		(8 "In3.Cu" signal "VCC1")
		(10 "In4.Cu" signal "GND1")
		(12 "In5.Cu" signal "IN1")
		(14 "In6.Cu" signal "GND2")
		(16 "In7.Cu" signal "IN2")
		(18 "In8.Cu" signal "GND3")
		(20 "In9.Cu" signal "IN3")
		(22 "In10.Cu" signal "GND4")
		(24 "In11.Cu" signal "IN4")
		(26 "In12.Cu" signal "GND5")
		(28 "In13.Cu" signal "IN5")
		(30 "In14.Cu" signal "GND6")
		(32 "In15.Cu" signal "IN6")
		(34 "In16.Cu" signal "GND7")
		(2 "B.Cu" signal "BOTTOM")
		(9 "F.Adhes" user "F.Adhesive")
		(11 "B.Adhes" user "B.Adhesive")
		(13 "F.Paste" user "Package Geometry/Pastemask Top")
		(15 "B.Paste" user "Package Geometry/Pastemask Bottom")
		(5 "F.SilkS" user "Ref Des/Silkscreen Top")
		(7 "B.SilkS" user "Ref Des/Silkscreen Bottom")
		(1 "F.Mask" user "Board Geometry/Soldermask Top")
		(3 "B.Mask" user "Board Geometry/Soldermask Bottom")
		(17 "Dwgs.User" user "User.Drawings")
		(19 "Cmts.User" user "User.Comments")
		(21 "Eco1.User" user "User.Eco1")
		(23 "Eco2.User" user "User.Eco2")
		(25 "Edge.Cuts" user "Board Geometry/Outline")
		(27 "Margin" user)
		(31 "F.CrtYd" user "Package Geometry/Place Bound Top")
		(29 "B.CrtYd" user "Package Geometry/Place Bound Bottom")
		(35 "F.Fab" user "Ref Des/Assembly Top")
		(33 "B.Fab" user "Ref Des/Assembly Bottom")
	)
	(footprint ""
		(layer "F.Cu")
		(at 59.649868 -295.89984)
		(property "Reference" "PEX0"
			(at -3.360166 35.566858 0)
			(unlocked yes)
			(layer "F.SilkS")
			(effects
				(font
					(size 2.032 1.524)
					(thickness 0.1524)
				)
				(justify left)
			)
		)
		(property "Value" ""
			(at 0 0 0)
			(layer "F.Fab")
			(effects
				(font
					(size 1.27 1.27)
				)
			)
		)
		(duplicate_pad_numbers_are_jumpers no)
		(pad "Y9" smd circle
			(at -15.200122 -4.750054)
			(size 0.4572 0.4572)
			(layers "F.Cu" "F.Mask" "F.Paste")
			(net "GND")
		)
		(pad "Y10" smd circle
			(at -14.249908 -4.750054)
			(size 0.4572 0.4572)
			(layers "F.Cu" "F.Mask" "F.Paste")
			(net "GND")
		)
		(pad "Y11" smd circle
			(at -13.299948 -4.750054)
			(size 0.4572 0.4572)
			(layers "F.Cu" "F.Mask" "F.Paste")
			(net "GND")
		)
		(pad "Y12" smd circle
			(at -12.349988 -4.750054)
			(size 0.4572 0.4572)
			(layers "F.Cu" "F.Mask" "F.Paste")
			(net "P1V8_PEX")
		)
		(pad "Y13" smd circle
			(at -11.400028 -4.750054)
			(size 0.4572 0.4572)
			(layers "F.Cu" "F.Mask" "F.Paste")
			(net "GND")
		)
		(pad "Y14" smd circle
			(at -10.450068 -4.750054)
			(size 0.4572 0.4572)
			(layers "F.Cu" "F.Mask" "F.Paste")
			(net "P0V8_PEX0")
		)
		(pad "Y15" smd circle
			(at -9.500108 -4.750054)
			(size 0.4572 0.4572)
			(layers "F.Cu" "F.Mask" "F.Paste")
			(net "GND")
		)
		(pad "Y16" smd circle
			(at -8.549894 -4.750054)
			(size 0.4572 0.4572)
			(layers "F.Cu" "F.Mask" "F.Paste")
			(net "P0V8_SERDES_VDDA_PEX0")
		)
		(pad "Y17" smd circle
			(at -7.599934 -4.750054)
			(size 0.4572 0.4572)
			(layers "F.Cu" "F.Mask" "F.Paste")
			(net "P0V8_SERDES_VDDA_PEX0")
		)
		(pad "Y18" smd circle
			(at -6.649974 -4.750054)
			(size 0.4572 0.4572)
			(layers "F.Cu" "F.Mask" "F.Paste")
			(net "P0V8_SERDES_VDDA_PEX0")
		)
		(pad "Y19" smd circle
			(at -5.700014 -4.750054)
			(size 0.4572 0.4572)
			(layers "F.Cu" "F.Mask" "F.Paste")
			(net "P0V8_SERDES_VDDA_PEX0")
		)
		(pad "Y20" smd circle
			(at -4.750054 -4.750054)
			(size 0.4572 0.4572)
			(layers "F.Cu" "F.Mask" "F.Paste")
			(net "P0V8_SERDES_VDDA_PEX0")
		)
		(pad "Y21" smd circle
			(at -3.800094 -4.750054)
			(size 0.4572 0.4572)
			(layers "F.Cu" "F.Mask" "F.Paste")
			(net "P0V8_SERDES_VDDA_PEX0")
		)
		(pad "Y22" smd circle
			(at -2.84988 -4.750054)
			(size 0.4572 0.4572)
			(layers "F.Cu" "F.Mask" "F.Paste")
			(net "P0V8_SERDES_VDDA_PEX0")
		)
		(pad "Y23" smd circle
			(at -1.89992 -4.750054)
			(size 0.4572 0.4572)
			(layers "F.Cu" "F.Mask" "F.Paste")
			(net "P0V8_SERDES_VDDA_PEX0")
		)
		(pad "Y24" smd circle
			(at -0.94996 -4.750054)
			(size 0.4572 0.4572)
			(layers "F.Cu" "F.Mask" "F.Paste")
			(net "P0V8_SERDES_VDDA_PEX0")
		)
		(pad "Y25" smd circle
			(at 0 -4.750054)
			(size 0.4572 0.4572)
			(layers "F.Cu" "F.Mask" "F.Paste")
			(net "P0V8_SERDES_VDDA_PEX0")
		)
		(pad "Y26" smd circle
			(at 0.94996 -4.750054)
			(size 0.4572 0.4572)
			(layers "F.Cu" "F.Mask" "F.Paste")
			(net "P0V8_SERDES_VDDA_PEX0")
		)
		(pad "Y27" smd circle
			(at 1.89992 -4.750054)
			(size 0.4572 0.4572)
			(layers "F.Cu" "F.Mask" "F.Paste")
			(net "P0V8_SERDES_VDDA_PEX0")
		)
		(pad "Y28" smd circle
			(at 2.84988 -4.750054)
			(size 0.4572 0.4572)
			(layers "F.Cu" "F.Mask" "F.Paste")
			(net "P0V8_SERDES_VDDA_PEX0")
		)
		(pad "Y29" smd circle
			(at 3.800094 -4.750054)
			(size 0.4572 0.4572)
			(layers "F.Cu" "F.Mask" "F.Paste")
			(net "P0V8_SERDES_VDDA_PEX0")
		)
		(pad "Y30" smd circle
			(at 4.750054 -4.750054)
			(size 0.4572 0.4572)
			(layers "F.Cu" "F.Mask" "F.Paste")
			(net "P0V8_SERDES_VDDA_PEX0")
		)
		(pad "Y31" smd circle
			(at 5.700014 -4.750054)
			(size 0.4572 0.4572)
			(layers "F.Cu" "F.Mask" "F.Paste")
			(net "P0V8_SERDES_VDDA_PEX0")
		)
		(pad "Y32" smd circle
			(at 6.649974 -4.750054)
			(size 0.4572 0.4572)
			(layers "F.Cu" "F.Mask" "F.Paste")
			(net "P0V8_SERDES_VDDA_PEX0")
		)
		(pad "Y33" smd circle
			(at 7.599934 -4.750054)
			(size 0.4572 0.4572)
			(layers "F.Cu" "F.Mask" "F.Paste")
			(net "P0V8_SERDES_VDDA_PEX0")
		)
		(pad "Y34" smd circle
			(at 8.549894 -4.750054)
			(size 0.4572 0.4572)
			(layers "F.Cu" "F.Mask" "F.Paste")
			(net "GND")
		)
		(pad "Y35" smd circle
			(at 9.500108 -4.750054)
			(size 0.4572 0.4572)
			(layers "F.Cu" "F.Mask" "F.Paste")
			(net "P1V8_PEX")
		)
		(pad "Y36" smd circle
			(at 10.450068 -4.750054)
			(size 0.4572 0.4572)
			(layers "F.Cu" "F.Mask" "F.Paste")
			(net "GND")
		)
		(pad "Y37" smd circle
			(at 11.400028 -4.750054)
			(size 0.4572 0.4572)
			(layers "F.Cu" "F.Mask" "F.Paste")
			(net "GND")
		)
		(pad "Y38" smd circle
			(at 12.349988 -4.750054)
			(size 0.4572 0.4572)
			(layers "F.Cu" "F.Mask" "F.Paste")
			(net "GND")
		)
		(pad "Y39" smd circle
			(at 13.299948 -4.750054)
			(size 0.4572 0.4572)
			(layers "F.Cu" "F.Mask" "F.Paste")
			(net "PEX0_ADCTEMP_VINP0")
		)
		(pad "Y40" smd circle
			(at 14.249908 -4.750054)
			(size 0.4572 0.4572)
			(layers "F.Cu" "F.Mask" "F.Paste")
			(net "GND")
		)
		(pad "Y41" smd circle
			(at 15.200122 -4.750054)
			(size 0.4572 0.4572)
			(layers "F.Cu" "F.Mask" "F.Paste")
			(net "Net_2817")
		)
		(pad "Y42" smd circle
			(at 16.150082 -4.750054)
			(size 0.4572 0.4572)
			(layers "F.Cu" "F.Mask" "F.Paste")
			(net "Net_2801")
		)
		(pad "Y43" smd circle
			(at 17.100042 -4.750054)
			(size 0.4572 0.4572)
			(layers "F.Cu" "F.Mask" "F.Paste")
			(net "GND")
		)
		(pad "Y44" smd circle
			(at 18.050002 -4.750054)
			(size 0.4572 0.4572)
			(layers "F.Cu" "F.Mask" "F.Paste")
			(net "GND")
		)
		(pad "Y45" smd circle
			(at 18.999962 -4.750054)
			(size 0.4572 0.4572)
			(layers "F.Cu" "F.Mask" "F.Paste")
			(net "GND")
		)
		(pad "Y46" smd circle
			(at 19.949922 -4.750054)
			(size 0.4572 0.4572)
			(layers "F.Cu" "F.Mask" "F.Paste")
			(net "GND")
		)
		(pad "Y47" smd circle
			(at 20.899882 -4.750054)
			(size 0.4572 0.4572)
			(layers "F.Cu" "F.Mask" "F.Paste")
			(net "GND")
		)
		(pad "Y48" smd circle
			(at 21.850096 -4.750054)
			(size 0.4572 0.4572)
			(layers "F.Cu" "F.Mask" "F.Paste")
			(net "Net_2785")
		)
		(pad "Y49" smd circle
			(at 22.800056 -4.750054)
			(size 0.4572 0.4572)
			(layers "F.Cu" "F.Mask" "F.Paste")
			(net "Net_2769")
		)
	)
)
